# BASEBOARD_FAB2 (Tioga Pass) — schematic netlist excerpt (pin names and nets, part order shuffled) for the footprints in the layout excerpt that follows; sources: Cadence DE-HDL packaged netlist, KiCad conversion of Wiwynn_Tioga_Pass_MB.brd

R6U7  RES  0.0 5% CHIP  pkg 0402  page 229 : A = P3V3 ; B = VR_PVTT_GHJ_BIAS
CR3W1  DIODE  BAT54WS IC  pkg SMLF  page 249 : C = BMC_SELF_HW_D_RST ; A = BMC_SELF_HW_RST

(kicad_pcb
	(version 20260206)
	(generator "pcbnew")
	(generator_version "10.0")
	(general
		(thickness 1.6)
		(legacy_teardrops no)
	)
	(paper "A4")
	(title_block
		(title "Wiwynn_Tioga_Pass_MB.brd")
		(comment 1 "Tioga Pass / footprints 2996-2997 of 4770")
	)
	(layers
		(0 "F.Cu" signal "TOP")
		(4 "In1.Cu" signal "L2GND")
		(6 "In2.Cu" signal "L3")
		(8 "In3.Cu" signal "L4GND")
		(10 "In4.Cu" signal "L5")
		(12 "In5.Cu" signal "L6GND")
		(14 "In6.Cu" signal "L7VCC")
		(16 "In7.Cu" signal "L8VCC")
		(18 "In8.Cu" signal "L9GND")
		(20 "In9.Cu" signal "L10")
		(22 "In10.Cu" signal "L11GND")
		(24 "In11.Cu" signal "L12")
		(26 "In12.Cu" signal "L13GND")
		(2 "B.Cu" signal "BOTTOM")
		(9 "F.Adhes" user "F.Adhesive")
		(11 "B.Adhes" user "B.Adhesive")
		(13 "F.Paste" user "Package Geometry/Pastemask Top")
		(15 "B.Paste" user "Package Geometry/Pastemask Bottom")
		(5 "F.SilkS" user "Ref Des/Silkscreen Top")
		(7 "B.SilkS" user "Ref Des/Silkscreen Bottom")
		(1 "F.Mask" user "Board Geometry/Soldermask Top")
		(3 "B.Mask" user "Board Geometry/Soldermask Bottom")
		(17 "Dwgs.User" user "User.Drawings")
		(19 "Cmts.User" user "User.Comments")
		(21 "Eco1.User" user "User.Eco1")
		(23 "Eco2.User" user "User.Eco2")
		(25 "Edge.Cuts" user "Board Geometry/Outline")
		(27 "Margin" user)
		(31 "F.CrtYd" user "Package Geometry/Place Bound Top")
		(29 "B.CrtYd" user "Package Geometry/Place Bound Bottom")
		(35 "F.Fab" user "Ref Des/Assembly Top")
		(33 "B.Fab" user "Ref Des/Assembly Bottom")
	)
	(footprint ""
		(layer "B.Cu")
		(at 451.517512 -15.84833 -90)
		(property "Reference" "CR3W1"
			(at -1.06934 -0.39116 0)
			(unlocked yes)
			(layer "B.SilkS")
			(effects
				(font
					(size 0.4064 0.254)
					(thickness 0.1524)
				)
				(justify left mirror)
			)
		)
		(property "Value" ""
			(at 0 0 90)
			(layer "B.Fab")
			(effects
				(font
					(size 1.27 1.27)
				)
				(justify mirror)
			)
		)
		(duplicate_pad_numbers_are_jumpers no)
		(fp_line
			(start 1.335278 2.576068)
			(end 1.335278 1.664462)
			(stroke
				(width 0.1524)
				(type default)
			)
			(layer "B.SilkS")
		)
		(fp_line
			(start 0.854456 1.664462)
			(end 1.335278 1.664462)
			(stroke
				(width 0.1524)
				(type default)
			)
			(layer "B.SilkS")
		)
		(fp_line
			(start 1.335278 1.664462)
			(end 1.8161 1.664462)
			(stroke
				(width 0.1524)
				(type default)
			)
			(layer "B.SilkS")
		)
		(fp_line
			(start 1.8161 1.664462)
			(end 1.335278 0.831596)
			(stroke
				(width 0.1524)
				(type default)
			)
			(layer "B.SilkS")
		)
		(fp_line
			(start 0.854456 0.831596)
			(end 1.8161 0.831596)
			(stroke
				(width 0.1524)
				(type default)
			)
			(layer "B.SilkS")
		)
		(fp_line
			(start 1.335278 0.831596)
			(end 0.854456 1.664462)
			(stroke
				(width 0.1524)
				(type default)
			)
			(layer "B.SilkS")
		)
		(fp_line
			(start 1.335278 -0.291846)
			(end 1.335278 0.831596)
			(stroke
				(width 0.1524)
				(type default)
			)
			(layer "B.SilkS")
		)
		(fp_poly
			(pts
				(xy 0.67437 0.24384) (xy 0.67437 2.04216) (xy -0.67437 2.04216) (xy -0.67437 0.24384)
			)
			(stroke
				(width 0)
				(type default)
			)
			(fill no)
			(layer "B.CrtYd")
		)
		(fp_line
			(start -0.67437 2.04216)
			(end -0.67437 0.24384)
			(stroke
				(width 0.1)
				(type default)
			)
			(layer "B.Fab")
		)
		(fp_line
			(start 0.67437 2.04216)
			(end -0.67437 2.04216)
			(stroke
				(width 0.1)
				(type default)
			)
			(layer "B.Fab")
		)
		(fp_line
			(start 0.854456 1.664462)
			(end 1.8161 1.664462)
			(stroke
				(width 0.1)
				(type default)
			)
			(layer "B.Fab")
		)
		(fp_line
			(start 1.335278 1.664462)
			(end 1.335278 2.576068)
			(stroke
				(width 0.1)
				(type default)
			)
			(layer "B.Fab")
		)
		(fp_line
			(start 1.8161 1.664462)
			(end 1.335278 0.831596)
			(stroke
				(width 0.1)
				(type default)
			)
			(layer "B.Fab")
		)
		(fp_line
			(start 0.854456 0.831596)
			(end 1.8161 0.831596)
			(stroke
				(width 0.1)
				(type default)
			)
			(layer "B.Fab")
		)
		(fp_line
			(start 1.335278 0.831596)
			(end 0.854456 1.664462)
			(stroke
				(width 0.1)
				(type default)
			)
			(layer "B.Fab")
		)
		(fp_line
			(start 1.335278 0.831596)
			(end 1.335278 -0.291846)
			(stroke
				(width 0.1)
				(type default)
			)
			(layer "B.Fab")
		)
		(fp_line
			(start -0.67437 0.24384)
			(end 0.67437 0.24384)
			(stroke
				(width 0.1)
				(type default)
			)
			(layer "B.Fab")
		)
		(fp_line
			(start 0.67437 0.24384)
			(end 0.67437 2.04216)
			(stroke
				(width 0.1)
				(type default)
			)
			(layer "B.Fab")
		)
		(pad "1" smd rect
			(at 0 0 90)
			(size 0.4064 1.016)
			(layers "B.Cu" "B.Mask" "B.Paste")
			(net "BMC_SELF_HW_D_RST")
		)
		(pad "2" smd rect
			(at 0 2.286 90)
			(size 0.4064 1.016)
			(layers "B.Cu" "B.Mask" "B.Paste")
			(net "BMC_SELF_HW_RST")
		)
	)
	(footprint ""
		(layer "B.Cu")
		(at 174.6123 -3.683 -90)
		(property "Reference" "R6U7"
			(at 0 0 90)
			(layer "B.SilkS")
			(hide yes)
			(effects
				(font
					(size 1.27 1.27)
				)
				(justify mirror)
			)
		)
		(property "Value" ""
			(at 0 0 90)
			(layer "B.Fab")
			(effects
				(font
					(size 1.27 1.27)
				)
				(justify mirror)
			)
		)
		(duplicate_pad_numbers_are_jumpers no)
		(fp_rect
			(start -0.2794 -0.1016)
			(end 0.2794 0.9906)
			(stroke
				(width 0)
				(type default)
			)
			(fill no)
			(layer "B.CrtYd")
		)
		(fp_line
			(start -0.2794 0.9906)
			(end -0.2794 -0.1016)
			(stroke
				(width 0.1)
				(type default)
			)
			(layer "B.Fab")
		)
		(fp_line
			(start 0.2794 0.9906)
			(end -0.2794 0.9906)
			(stroke
				(width 0.1)
				(type default)
			)
			(layer "B.Fab")
		)
		(fp_line
			(start -0.2794 -0.1016)
			(end 0.2794 -0.1016)
			(stroke
				(width 0.1)
				(type default)
			)
			(layer "B.Fab")
		)
		(fp_line
			(start 0.2794 -0.1016)
			(end 0.2794 0.9906)
			(stroke
				(width 0.1)
				(type default)
			)
			(layer "B.Fab")
		)
		(pad "1" smd rect
			(at 0 0 90)
			(size 0.508 0.508)
			(layers "B.Cu" "B.Mask" "B.Paste")
			(net "P3V3")
		)
		(pad "2" smd rect
			(at 0 0.889 90)
			(size 0.508 0.508)
			(layers "B.Cu" "B.Mask" "B.Paste")
			(net "VR_PVTT_GHJ_BIAS")
		)
		(zone
			(layer "B.Cu")
			(hatch none 0.5)
			(connect_pads
				(clearance 0)
			)
			(min_thickness 0.25)
			(keepout
				(tracks not_allowed)
				(vias allowed)
				(pads allowed)
				(copperpour not_allowed)
				(footprints allowed)
			)
			(placement
				(enabled no)
				(sheetname "")
			)
			(fill
				(thermal_gap 0.5)
				(thermal_bridge_width 0.5)
				(island_removal_mode 0)
			)
			(polygon
				(pts
					(xy 174.3583 -3.937) (xy 173.9773 -3.937) (xy 173.9773 -3.429) (xy 174.3583 -3.429)
				)
			)
		)
		(zone
			(layer "B.Cu")
			(hatch none 0.5)
			(connect_pads
				(clearance 0)
			)
			(min_thickness 0.25)
			(keepout
				(tracks allowed)
				(vias not_allowed)
				(pads allowed)
				(copperpour not_allowed)
				(footprints allowed)
			)
			(placement
				(enabled no)
				(sheetname "")
			)
			(fill
				(thermal_gap 0.5)
				(thermal_bridge_width 0.5)
				(island_removal_mode 0)
			)
			(polygon
				(pts
					(xy 174.3583 -3.937) (xy 173.9773 -3.937) (xy 173.9773 -3.429) (xy 174.3583 -3.429)
				)
			)
		)
	)
)
